# T6G (Grand Teton) — schematic netlist excerpt (pin names and nets, part order shuffled) for the footprints in the layout excerpt that follows; sources: Cadence DE-HDL packaged netlist, KiCad conversion of 04192023_DAF0TMB3IC0_F0TG_MB_C_brd_V02_OCP.brd

R6223  Q_RES  1K 1% CHIP  pkg 0402LF  page 176 : A = PD_USB_CPU0_WP ; B = GND
R444  Q_RES  4.7K 5% CHIP  pkg 0402LF  page 28 : A = FM_SMM_CRASHDUMP ; B = PVDD18_S5_P0

(kicad_pcb
	(version 20260206)
	(generator "pcbnew")
	(generator_version "10.0")
	(general
		(thickness 1.6)
		(legacy_teardrops no)
	)
	(paper "A4")
	(title_block
		(title "04192023_DAF0TMB3IC0_F0TG_MB_C_brd_V02_OCP.brd")
		(comment 1 "Grand Teton / footprints 6821-6822 of 8354")
	)
	(layers
		(0 "F.Cu" signal "TOP")
		(4 "In1.Cu" signal "GND")
		(6 "In2.Cu" signal "IN1")
		(8 "In3.Cu" signal "GND1")
		(10 "In4.Cu" signal "IN2")
		(12 "In5.Cu" signal "GND2")
		(14 "In6.Cu" signal "IN3")
		(16 "In7.Cu" signal "GND3")
		(18 "In8.Cu" signal "VCC")
		(20 "In9.Cu" signal "VCC1")
		(22 "In10.Cu" signal "GND4")
		(24 "In11.Cu" signal "IN4")
		(26 "In12.Cu" signal "GND5")
		(28 "In13.Cu" signal "IN5")
		(30 "In14.Cu" signal "GND6")
		(32 "In15.Cu" signal "IN6")
		(34 "In16.Cu" signal "GND7")
		(2 "B.Cu" signal "BOTTOM")
		(9 "F.Adhes" user "F.Adhesive")
		(11 "B.Adhes" user "B.Adhesive")
		(13 "F.Paste" user "Package Geometry/Pastemask Top")
		(15 "B.Paste" user "Package Geometry/Pastemask Bottom")
		(5 "F.SilkS" user "Ref Des/Silkscreen Top")
		(7 "B.SilkS" user "Ref Des/Silkscreen Bottom")
		(1 "F.Mask" user "Board Geometry/Soldermask Top")
		(3 "B.Mask" user "Board Geometry/Soldermask Bottom")
		(17 "Dwgs.User" user "User.Drawings")
		(19 "Cmts.User" user "User.Comments")
		(21 "Eco1.User" user "User.Eco1")
		(23 "Eco2.User" user "User.Eco2")
		(25 "Edge.Cuts" user "Board Geometry/Outline")
		(27 "Margin" user)
		(31 "F.CrtYd" user "Package Geometry/Place Bound Top")
		(29 "B.CrtYd" user "Package Geometry/Place Bound Bottom")
		(35 "F.Fab" user "Ref Des/Assembly Top")
		(33 "B.Fab" user "Ref Des/Assembly Bottom")
	)
	(footprint ""
		(layer "B.Cu")
		(at 110.16234 -62.01791 90)
		(property "Reference" "R6223"
			(at 0 0 90)
			(layer "B.SilkS")
			(hide yes)
			(effects
				(font
					(size 1.27 1.27)
				)
				(justify mirror)
			)
		)
		(property "Value" ""
			(at 0 0 90)
			(layer "B.Fab")
			(effects
				(font
					(size 1.27 1.27)
				)
				(justify mirror)
			)
		)
		(duplicate_pad_numbers_are_jumpers no)
		(fp_line
			(start 0.7874 -0.4064)
			(end -0.7874 -0.4064)
			(stroke
				(width 0.1524)
				(type default)
			)
			(layer "B.SilkS")
		)
		(fp_line
			(start -0.7874 -0.4064)
			(end -0.7874 0.4064)
			(stroke
				(width 0.1524)
				(type default)
			)
			(layer "B.SilkS")
		)
		(fp_line
			(start 0.7874 0.4064)
			(end 0.7874 -0.4064)
			(stroke
				(width 0.1524)
				(type default)
			)
			(layer "B.SilkS")
		)
		(fp_line
			(start -0.7874 0.4064)
			(end 0.7874 0.4064)
			(stroke
				(width 0.1524)
				(type default)
			)
			(layer "B.SilkS")
		)
		(fp_line
			(start 0.67945 -0.305054)
			(end 0.12065 -0.305054)
			(stroke
				(width 0.1)
				(type default)
			)
			(layer "B.Fab")
		)
		(fp_line
			(start 0.12065 -0.305054)
			(end 0.12065 -0.2794)
			(stroke
				(width 0.1)
				(type default)
			)
			(layer "B.Fab")
		)
		(fp_line
			(start -0.12065 -0.3048)
			(end -0.67945 -0.3048)
			(stroke
				(width 0.1)
				(type default)
			)
			(layer "B.Fab")
		)
		(fp_line
			(start -0.67945 -0.3048)
			(end -0.67945 0.3048)
			(stroke
				(width 0.1)
				(type default)
			)
			(layer "B.Fab")
		)
		(fp_line
			(start 0.12065 -0.2794)
			(end -0.12065 -0.2794)
			(stroke
				(width 0.1)
				(type default)
			)
			(layer "B.Fab")
		)
		(fp_line
			(start -0.12065 -0.2794)
			(end -0.12065 -0.3048)
			(stroke
				(width 0.1)
				(type default)
			)
			(layer "B.Fab")
		)
		(fp_line
			(start 0.12065 0.2794)
			(end 0.12065 0.3048)
			(stroke
				(width 0.1)
				(type default)
			)
			(layer "B.Fab")
		)
		(fp_line
			(start -0.120396 0.2794)
			(end 0.12065 0.2794)
			(stroke
				(width 0.1)
				(type default)
			)
			(layer "B.Fab")
		)
		(fp_line
			(start 0.67945 0.3048)
			(end 0.67945 -0.305054)
			(stroke
				(width 0.1)
				(type default)
			)
			(layer "B.Fab")
		)
		(fp_line
			(start 0.12065 0.3048)
			(end 0.67945 0.3048)
			(stroke
				(width 0.1)
				(type default)
			)
			(layer "B.Fab")
		)
		(fp_line
			(start -0.120396 0.3048)
			(end -0.120396 0.2794)
			(stroke
				(width 0.1)
				(type default)
			)
			(layer "B.Fab")
		)
		(fp_line
			(start -0.67945 0.3048)
			(end -0.120396 0.3048)
			(stroke
				(width 0.1)
				(type default)
			)
			(layer "B.Fab")
		)
		(pad "1" smd circle
			(at 0.40005 0 270)
			(size 0 0)
			(layers "B.Cu" "B.Mask" "B.Paste")
			(net "PD_USB_CPU0_WP")
		)
		(pad "2" smd circle
			(at -0.40005 0 270)
			(size 0 0)
			(layers "B.Cu" "B.Mask" "B.Paste")
			(net "GND")
		)
	)
	(footprint ""
		(layer "B.Cu")
		(at 406.698958 -329.942952 180)
		(property "Reference" "R444"
			(at 0 0 0)
			(layer "B.SilkS")
			(hide yes)
			(effects
				(font
					(size 1.27 1.27)
				)
				(justify mirror)
			)
		)
		(property "Value" ""
			(at 0 0 0)
			(layer "B.Fab")
			(effects
				(font
					(size 1.27 1.27)
				)
				(justify mirror)
			)
		)
		(duplicate_pad_numbers_are_jumpers no)
		(fp_line
			(start 0.7874 0.4064)
			(end 0.7874 -0.4064)
			(stroke
				(width 0.1524)
				(type default)
			)
			(layer "B.SilkS")
		)
		(fp_line
			(start 0.7874 -0.4064)
			(end -0.7874 -0.4064)
			(stroke
				(width 0.1524)
				(type default)
			)
			(layer "B.SilkS")
		)
		(fp_line
			(start -0.7874 0.4064)
			(end 0.7874 0.4064)
			(stroke
				(width 0.1524)
				(type default)
			)
			(layer "B.SilkS")
		)
		(fp_line
			(start -0.7874 -0.4064)
			(end -0.7874 0.4064)
			(stroke
				(width 0.1524)
				(type default)
			)
			(layer "B.SilkS")
		)
		(fp_line
			(start 0.67945 0.3048)
			(end 0.67945 -0.305054)
			(stroke
				(width 0.1)
				(type default)
			)
			(layer "B.Fab")
		)
		(fp_line
			(start 0.67945 -0.305054)
			(end 0.12065 -0.305054)
			(stroke
				(width 0.1)
				(type default)
			)
			(layer "B.Fab")
		)
		(fp_line
			(start 0.12065 0.3048)
			(end 0.67945 0.3048)
			(stroke
				(width 0.1)
				(type default)
			)
			(layer "B.Fab")
		)
		(fp_line
			(start 0.12065 0.2794)
			(end 0.12065 0.3048)
			(stroke
				(width 0.1)
				(type default)
			)
			(layer "B.Fab")
		)
		(fp_line
			(start 0.12065 -0.2794)
			(end -0.12065 -0.2794)
			(stroke
				(width 0.1)
				(type default)
			)
			(layer "B.Fab")
		)
		(fp_line
			(start 0.12065 -0.305054)
			(end 0.12065 -0.2794)
			(stroke
				(width 0.1)
				(type default)
			)
			(layer "B.Fab")
		)
		(fp_line
			(start -0.120396 0.3048)
			(end -0.120396 0.2794)
			(stroke
				(width 0.1)
				(type default)
			)
			(layer "B.Fab")
		)
		(fp_line
			(start -0.120396 0.2794)
			(end 0.12065 0.2794)
			(stroke
				(width 0.1)
				(type default)
			)
			(layer "B.Fab")
		)
		(fp_line
			(start -0.12065 -0.2794)
			(end -0.12065 -0.3048)
			(stroke
				(width 0.1)
				(type default)
			)
			(layer "B.Fab")
		)
		(fp_line
			(start -0.12065 -0.3048)
			(end -0.67945 -0.3048)
			(stroke
				(width 0.1)
				(type default)
			)
			(layer "B.Fab")
		)
		(fp_line
			(start -0.67945 0.3048)
			(end -0.120396 0.3048)
			(stroke
				(width 0.1)
				(type default)
			)
			(layer "B.Fab")
		)
		(fp_line
			(start -0.67945 -0.3048)
			(end -0.67945 0.3048)
			(stroke
				(width 0.1)
				(type default)
			)
			(layer "B.Fab")
		)
		(pad "1" smd circle
			(at 0.40005 0)
			(size 0 0)
			(layers "B.Cu" "B.Mask" "B.Paste")
			(net "FM_SMM_CRASHDUMP")
		)
		(pad "2" smd circle
			(at -0.40005 0)
			(size 0 0)
			(layers "B.Cu" "B.Mask" "B.Paste")
			(net "PVDD18_S5_P0")
		)
	)
)
